# S9S_MB_2U (Grand Teton) — schematic netlist excerpt (pin names and nets, part order shuffled) for the footprints in the layout excerpt that follows; sources: Cadence DE-HDL packaged netlist, KiCad conversion of 03242023_DA0F0TMBIJ0_F0T_Motherboard_J_brd_V01_OCP.brd

R988  Q_RES  33.2 1% CHIP  pkg 0402LF  page 222 : A = FM_PVCCFA_EHV_FIVRA_CPU1_R_EN ; B = FM_PVCCFA_EHV_FIVRA_CPU1_EN
PR3932  Q_RES  4.99K 0.1% CHIP  pkg 0402LF  page 301 : A = HSC_VOSEN ; B = AGND_HSC

(kicad_pcb
	(version 20260206)
	(generator "pcbnew")
	(generator_version "10.0")
	(general
		(thickness 1.6)
		(legacy_teardrops no)
	)
	(paper "A4")
	(title_block
		(title "03242023_DA0F0TMBIJ0_F0T_Motherboard_J_brd_V01_OCP.brd")
		(comment 1 "Grand Teton / footprints 6051-6052 of 6105")
	)
	(layers
		(0 "F.Cu" signal "TOP")
		(4 "In1.Cu" signal "GND")
		(6 "In2.Cu" signal "IN1")
		(8 "In3.Cu" signal "GND1")
		(10 "In4.Cu" signal "IN2")
		(12 "In5.Cu" signal "GND2")
		(14 "In6.Cu" signal "IN3")
		(16 "In7.Cu" signal "GND3")
		(18 "In8.Cu" signal "VCC")
		(20 "In9.Cu" signal "VCC1")
		(22 "In10.Cu" signal "GND4")
		(24 "In11.Cu" signal "IN4")
		(26 "In12.Cu" signal "GND5")
		(28 "In13.Cu" signal "IN5")
		(30 "In14.Cu" signal "GND6")
		(32 "In15.Cu" signal "IN6")
		(34 "In16.Cu" signal "GND7")
		(2 "B.Cu" signal "BOTTOM")
		(9 "F.Adhes" user "F.Adhesive")
		(11 "B.Adhes" user "B.Adhesive")
		(13 "F.Paste" user "Package Geometry/Pastemask Top")
		(15 "B.Paste" user "Package Geometry/Pastemask Bottom")
		(5 "F.SilkS" user "Ref Des/Silkscreen Top")
		(7 "B.SilkS" user "Ref Des/Silkscreen Bottom")
		(1 "F.Mask" user "Board Geometry/Soldermask Top")
		(3 "B.Mask" user "Board Geometry/Soldermask Bottom")
		(17 "Dwgs.User" user "User.Drawings")
		(19 "Cmts.User" user "User.Comments")
		(21 "Eco1.User" user "User.Eco1")
		(23 "Eco2.User" user "User.Eco2")
		(25 "Edge.Cuts" user "Board Geometry/Outline")
		(27 "Margin" user)
		(31 "F.CrtYd" user "Package Geometry/Place Bound Top")
		(29 "B.CrtYd" user "Package Geometry/Place Bound Bottom")
		(35 "F.Fab" user "Ref Des/Assembly Top")
		(33 "B.Fab" user "Ref Des/Assembly Bottom")
	)
	(footprint ""
		(layer "B.Cu")
		(at 183.172608 -398.651222)
		(property "Reference" "PR3932"
			(at 0 0 0)
			(layer "B.SilkS")
			(hide yes)
			(effects
				(font
					(size 1.27 1.27)
				)
				(justify mirror)
			)
		)
		(property "Value" ""
			(at 0 0 0)
			(layer "B.Fab")
			(effects
				(font
					(size 1.27 1.27)
				)
				(justify mirror)
			)
		)
		(duplicate_pad_numbers_are_jumpers no)
		(fp_line
			(start -0.7874 -0.4064)
			(end -0.7874 0.4064)
			(stroke
				(width 0.1524)
				(type default)
			)
			(layer "B.SilkS")
		)
		(fp_line
			(start -0.7874 0.4064)
			(end 0.7874 0.4064)
			(stroke
				(width 0.1524)
				(type default)
			)
			(layer "B.SilkS")
		)
		(fp_line
			(start 0.7874 -0.4064)
			(end -0.7874 -0.4064)
			(stroke
				(width 0.1524)
				(type default)
			)
			(layer "B.SilkS")
		)
		(fp_line
			(start 0.7874 0.4064)
			(end 0.7874 -0.4064)
			(stroke
				(width 0.1524)
				(type default)
			)
			(layer "B.SilkS")
		)
		(fp_line
			(start -0.67945 -0.3048)
			(end -0.67945 0.3048)
			(stroke
				(width 0.1)
				(type default)
			)
			(layer "B.Fab")
		)
		(fp_line
			(start -0.67945 0.3048)
			(end -0.120396 0.3048)
			(stroke
				(width 0.1)
				(type default)
			)
			(layer "B.Fab")
		)
		(fp_line
			(start -0.12065 -0.3048)
			(end -0.67945 -0.3048)
			(stroke
				(width 0.1)
				(type default)
			)
			(layer "B.Fab")
		)
		(fp_line
			(start -0.12065 -0.2794)
			(end -0.12065 -0.3048)
			(stroke
				(width 0.1)
				(type default)
			)
			(layer "B.Fab")
		)
		(fp_line
			(start -0.120396 0.2794)
			(end 0.12065 0.2794)
			(stroke
				(width 0.1)
				(type default)
			)
			(layer "B.Fab")
		)
		(fp_line
			(start -0.120396 0.3048)
			(end -0.120396 0.2794)
			(stroke
				(width 0.1)
				(type default)
			)
			(layer "B.Fab")
		)
		(fp_line
			(start 0.12065 -0.305054)
			(end 0.12065 -0.2794)
			(stroke
				(width 0.1)
				(type default)
			)
			(layer "B.Fab")
		)
		(fp_line
			(start 0.12065 -0.2794)
			(end -0.12065 -0.2794)
			(stroke
				(width 0.1)
				(type default)
			)
			(layer "B.Fab")
		)
		(fp_line
			(start 0.12065 0.2794)
			(end 0.12065 0.3048)
			(stroke
				(width 0.1)
				(type default)
			)
			(layer "B.Fab")
		)
		(fp_line
			(start 0.12065 0.3048)
			(end 0.67945 0.3048)
			(stroke
				(width 0.1)
				(type default)
			)
			(layer "B.Fab")
		)
		(fp_line
			(start 0.67945 -0.305054)
			(end 0.12065 -0.305054)
			(stroke
				(width 0.1)
				(type default)
			)
			(layer "B.Fab")
		)
		(fp_line
			(start 0.67945 0.3048)
			(end 0.67945 -0.305054)
			(stroke
				(width 0.1)
				(type default)
			)
			(layer "B.Fab")
		)
		(pad "1" smd circle
			(at 0.40005 0 180)
			(size 0 0)
			(layers "B.Cu" "B.Mask" "B.Paste")
			(net "HSC_VOSEN")
		)
		(pad "2" smd circle
			(at -0.40005 0 180)
			(size 0 0)
			(layers "B.Cu" "B.Mask" "B.Paste")
			(net "AGND_HSC")
		)
	)
	(footprint ""
		(layer "B.Cu")
		(at 160.83788 -123.916948)
		(property "Reference" "R988"
			(at 0 0 0)
			(layer "B.SilkS")
			(hide yes)
			(effects
				(font
					(size 1.27 1.27)
				)
				(justify mirror)
			)
		)
		(property "Value" ""
			(at 0 0 0)
			(layer "B.Fab")
			(effects
				(font
					(size 1.27 1.27)
				)
				(justify mirror)
			)
		)
		(duplicate_pad_numbers_are_jumpers no)
		(fp_line
			(start -0.7874 -0.4064)
			(end -0.7874 0.4064)
			(stroke
				(width 0.1524)
				(type default)
			)
			(layer "B.SilkS")
		)
		(fp_line
			(start -0.7874 0.4064)
			(end 0.7874 0.4064)
			(stroke
				(width 0.1524)
				(type default)
			)
			(layer "B.SilkS")
		)
		(fp_line
			(start 0.7874 -0.4064)
			(end -0.7874 -0.4064)
			(stroke
				(width 0.1524)
				(type default)
			)
			(layer "B.SilkS")
		)
		(fp_line
			(start 0.7874 0.4064)
			(end 0.7874 -0.4064)
			(stroke
				(width 0.1524)
				(type default)
			)
			(layer "B.SilkS")
		)
		(fp_line
			(start -0.67945 -0.3048)
			(end -0.67945 0.3048)
			(stroke
				(width 0.1)
				(type default)
			)
			(layer "B.Fab")
		)
		(fp_line
			(start -0.67945 0.3048)
			(end -0.120396 0.3048)
			(stroke
				(width 0.1)
				(type default)
			)
			(layer "B.Fab")
		)
		(fp_line
			(start -0.12065 -0.3048)
			(end -0.67945 -0.3048)
			(stroke
				(width 0.1)
				(type default)
			)
			(layer "B.Fab")
		)
		(fp_line
			(start -0.12065 -0.2794)
			(end -0.12065 -0.3048)
			(stroke
				(width 0.1)
				(type default)
			)
			(layer "B.Fab")
		)
		(fp_line
			(start -0.120396 0.2794)
			(end 0.12065 0.2794)
			(stroke
				(width 0.1)
				(type default)
			)
			(layer "B.Fab")
		)
		(fp_line
			(start -0.120396 0.3048)
			(end -0.120396 0.2794)
			(stroke
				(width 0.1)
				(type default)
			)
			(layer "B.Fab")
		)
		(fp_line
			(start 0.12065 -0.305054)
			(end 0.12065 -0.2794)
			(stroke
				(width 0.1)
				(type default)
			)
			(layer "B.Fab")
		)
		(fp_line
			(start 0.12065 -0.2794)
			(end -0.12065 -0.2794)
			(stroke
				(width 0.1)
				(type default)
			)
			(layer "B.Fab")
		)
		(fp_line
			(start 0.12065 0.2794)
			(end 0.12065 0.3048)
			(stroke
				(width 0.1)
				(type default)
			)
			(layer "B.Fab")
		)
		(fp_line
			(start 0.12065 0.3048)
			(end 0.67945 0.3048)
			(stroke
				(width 0.1)
				(type default)
			)
			(layer "B.Fab")
		)
		(fp_line
			(start 0.67945 -0.305054)
			(end 0.12065 -0.305054)
			(stroke
				(width 0.1)
				(type default)
			)
			(layer "B.Fab")
		)
		(fp_line
			(start 0.67945 0.3048)
			(end 0.67945 -0.305054)
			(stroke
				(width 0.1)
				(type default)
			)
			(layer "B.Fab")
		)
		(pad "1" smd circle
			(at 0.40005 0 180)
			(size 0 0)
			(layers "B.Cu" "B.Mask" "B.Paste")
			(net "FM_PVCCFA_EHV_FIVRA_CPU1_R_EN")
		)
		(pad "2" smd circle
			(at -0.40005 0 180)
			(size 0 0)
			(layers "B.Cu" "B.Mask" "B.Paste")
			(net "FM_PVCCFA_EHV_FIVRA_CPU1_EN")
		)
	)
)
